FILE_TYPE = CONNECTIVITY;
{Allegro Design Entry HDL 17.4-2019 S026 (4007227) 1/17/2022}
"PAGE_NUMBER" = 177;
0"NC";
1"GND\g";
2"GND\g";
3"GND\g";
4"GND\g";
5"GND\g";
6"GND\g";
7"GND\g";
8"GND\g";
9"GND\g";
10"GND\g";
11"GND\g";
12"PVDDCR_CPU1_P0_VOS3";
13"SW_PVDDCR_CPU1_P0_SW3";
14"SW_PVDDCR_CPU1_P0_BOOTR3";
15"GND\g";
16"SW_P12V_AUX_PVDDCR_CPU1_P0_FLT\g";
17"SW_PVDDCR_CPU1_P0_BOOT3_R";
18"SW_P12V_AUX_PVDDCR_CPU1_P0_FLT\g";
19"SW_PVDDCR_CPU1_P0_BOOT3";
20"SW_PVDDCR_CPU1_P0_BOOT4";
21"SW_PVDDCR_CPU1_P0_BOOT4_R";
22"SW_PVDDCR_CPU1_P0_SW3_RC";
23"PVDDCR_CPU1_P0_PVCC\g";
24"GND\g";
25"GND\g";
26"PVDDCR_CPU1_P0_PVCC\g";
27"GND\g";
28"GND\g";
29"PVDDCR_CPU1_P0\g";
30"GND\g";
31"PVDDCR_CPU1_P0\g";
32"PVDDCR_CPU1_P0_VCC4";
33"SW_PVDDCR_CPU1_P0_SW4";
34"PVDDCR_CPU1_P0_VCC3";
35"IND_CPU1_P0_CPL3";
36"IND_CPU1_P0_CPL2";
37"IND_CPU1_P0_CPL3";
38"SW_PVDDCR_CPU1_P0_SW4_RC";
39"PVDDCR_CPU1_P0_VOS4";
40"NC_PVDDCR_CPU1_P0_GL2_3";
41"NC_PVDDCR_CPU1_P0_GL1_3";
42"NC_PVDDCR_CPU1_P0_GL1_4";
43"NC_PVDDCR_CPU1_P0_GL2_4";
44"SW_PVDDCR_CPU1_P0_BOOTR4";
45"NC_PVDDCR_CPU1_P0_DNC3";
46"PVDDCR_CPU1_P0_IMON3";
47"PVDDCR_CPU1_P0_VCCS"CDS_PHYS_NET_NAME"PVDDCR_CPU1_P0_VCCS";
48"PVDDCR_CPU1_P0_LSET3";
49"NC_PVDDCR_CPU1_P0_DNC4";
50"PVDDCR_CPU1_P0_IMON4";
51"PVDDCR_CPU1_P0_TEMP0";
52"PVDDCR_CPU1_P0_PWM3";
53"PVDDCR_CPU1_P0_VCCS"CDS_PHYS_NET_NAME"PVDDCR_CPU1_P0_VCCS";
54"PVDDCR_CPU1_P0_TEMP0";
55"PVDDCR_CPU1_P0_PWM4";
56"PVDDCR_CPU1_P0_LSET4";
%"UNIVERSAL_GND"
"1","(825,950)","0","pure_quanta_power","I1";
;
CDS_LIB"pure_quanta_power"
HDL_POWER"GND";
"A"1;
%"UNIVERSAL_GND"
"1","(850,3775)","0","pure_quanta_power","I11";
;
CDS_LIB"pure_quanta_power"
HDL_POWER"GND";
"A"2;
%"Q_CAP"
"1","(850,3975)","0","pure_quanta","I12";
;
LOCATION"PC114_3"
$SEC"1"
CDS_SEC"1"
PACK_TYPE"0402"
VOLTAGE"25V"
VALUE"0.1UF"
TOLERANCE"10%"
MATERIAL"X7R"
CDS_LIB"pure_quanta"
PART_NUMBER"CH4104K1B00";
"B"
$PN"2"2;
"A"
$PN"1"47;
%"Q_RES"
"2","(1475,2525)","0","pure_quanta","I13";
;
LOCATION"PR87"
$SEC"1"
CDS_SEC"1"
WATTAGE"1/16W"
MATERIAL"CHIP"
TOLERANCE"1%"
VALUE"2.2"
PACK_TYPE"0402LF"
CDS_LIB"pure_quanta"
PART_NUMBER"CS-2202FB01";
"A"
$PN"1"23;
"B"
$PN"2"32;
%"VCC_CORE"
"1","(1475,2950)","0","pure_quanta_power","I14";
;
HDL_POWER"PVDDCR_CPU1_P0_PVCC"
CDS_LIB"pure_quanta_power";
"A"23;
%"UNIVERSAL_GND"
"1","(1825,2275)","0","pure_quanta_power","I15";
;
CDS_LIB"pure_quanta_power"
HDL_POWER"GND";
"A"3;
%"Q_CAP"
"1","(1825,2550)","0","pure_quanta","I16";
;
LOCATION"PC111_C1P0_4"
$SEC"1"
CDS_SEC"1"
PACK_TYPE"C0402"
VOLTAGE"10V"
VALUE"2.2UF"
TOLERANCE"10%"
MATERIAL"X6S"
CDS_LIB"pure_quanta"
PART_NUMBER"CH5222KEB01";
"B"
$PN"2"3;
"A"
$PN"1"23;
%"UNIVERSAL_GND"
"1","(1350,3625)","0","pure_quanta_power","I17";
;
CDS_LIB"pure_quanta_power"
HDL_POWER"GND";
"A"4;
%"Q_RES"
"2","(1350,3850)","2","pure_quanta","I18";
;
LOCATION"PR86"
$SEC"1"
CDS_SEC"1"
WATTAGE"1/16W"
MATERIAL"EMPTY"
TOLERANCE"1%"
VALUE"8.87K"
PACK_TYPE"0402LF"
CDS_LIB"pure_quanta"
PART_NUMBER"CS28872FB01";
"A"
$PN"1"48;
"B"
$PN"2"4;
%"Q_CAP"
"1","(825,1150)","0","pure_quanta","I2";
;
LOCATION"PC113_4"
$SEC"1"
CDS_SEC"1"
PACK_TYPE"0402"
VOLTAGE"25V"
VALUE"0.1UF"
TOLERANCE"10%"
MATERIAL"X7R"
CDS_LIB"pure_quanta"
PART_NUMBER"CH4104K1B00";
"B"
$PN"2"1;
"A"
$PN"1"53;
%"ISL99390FRZTR5935"
"1","(3250,1525)","0","pure_quanta","I21";
;
LOCATION"PU14"
$SEC"1"
CDS_SEC"1"
MATERIAL"IC"
VALUE"ISL99390FRZ-TR5935"
PART_TYPE"SMLF"
CDS_LIB"pure_quanta"
NEEDS_NO_SIZE"TRUE"
CDS_LMAN_SYM_OUTLINE"-300,700,250,-650"
PART_NUMBER"AL099390004";
"PGND2"
$PN"7_9-20_24"24;
"GL2"
$PN"41"43;
"GL1"
$PN"6"42;
"DNC"
$PN"31"49;
"EN"
$PN"35"32;
"PGND3"
$PN"40"24;
"VOS"
$PN"1"39;
"VIN2"
$PN"30"18;
"PGND1"
$PN"5"24;
"SW"
$PN"10_19"33;
"LSET"
$PN"37"56;
"IOUT"
$PN"38"50;
"TOUT_FLT"
$PN"36"54;
"PVCC"
$PN"4"23;
"PHASE"
$PN"32"44;
"VIN1"
$PN"25_29"18;
"BOOT"
$PN"33"20;
"AGND"
$PN"2"24;
"VCC"
$PN"3"32;
"REFIN"
$PN"39"53;
"PWM"
$PN"34"55;
%"UNIVERSAL_GND"
"1","(3900,800)","0","pure_quanta_power","I22";
;
CDS_LIB"pure_quanta_power"
HDL_POWER"GND";
"A"24;
%"ISL99390FRZTR5935"
"1","(3275,4350)","0","pure_quanta","I23";
;
LOCATION"PU15"
$SEC"1"
CDS_SEC"1"
VALUE"ISL99390FRZ-TR5935"
MATERIAL"IC"
PART_TYPE"SMLF"
CDS_LIB"pure_quanta"
NEEDS_NO_SIZE"TRUE"
CDS_LMAN_SYM_OUTLINE"-300,700,250,-650"
PART_NUMBER"AL099390004";
"PGND2"
$PN"7_9-20_24"25;
"GL2"
$PN"41"40;
"GL1"
$PN"6"41;
"DNC"
$PN"31"45;
"EN"
$PN"35"34;
"PGND3"
$PN"40"25;
"VOS"
$PN"1"12;
"VIN2"
$PN"30"16;
"PGND1"
$PN"5"25;
"SW"
$PN"10_19"13;
"LSET"
$PN"37"48;
"IOUT"
$PN"38"46;
"TOUT_FLT"
$PN"36"51;
"PVCC"
$PN"4"26;
"PHASE"
$PN"32"14;
"VIN1"
$PN"25_29"16;
"BOOT"
$PN"33"19;
"AGND"
$PN"2"25;
"VCC"
$PN"3"34;
"REFIN"
$PN"39"47;
"PWM"
$PN"34"52;
%"Q_CAP"
"1","(4050,2450)","0","pure_quanta","I24";
;
LOCATION"PC115_4"
$SEC"1"
CDS_SEC"1"
PACK_TYPE"0402"
VALUE"0.1UF"
TOLERANCE"10%"
MATERIAL"X7R"
VOLTAGE"25V"
CDS_LIB"pure_quanta"
PART_NUMBER"CH4104K1B00";
"B"
$PN"2"11;
"A"
$PN"1"18;
%"UNIVERSAL_GND"
"1","(3925,3625)","0","pure_quanta_power","I25";
;
CDS_LIB"pure_quanta_power"
HDL_POWER"GND";
"A"25;
%"Q_CAP"
"1","(1650,4800)","0","pure_quanta","I28";
;
LOCATION"PC110"
$SEC"1"
CDS_SEC"1"
VOLTAGE"10V"
VALUE"2.2UF"
TOLERANCE"10%"
MATERIAL"X6S"
PACK_TYPE"C0402"
CDS_LIB"pure_quanta"
PART_NUMBER"CH5222KEB01";
"B"
$PN"2"5;
"A"
$PN"1"34;
%"UNIVERSAL_GND"
"1","(1650,4600)","0","pure_quanta_power","I29";
;
CDS_LIB"pure_quanta_power"
HDL_POWER"GND";
"A"5;
%"UNIVERSAL_GND"
"1","(1325,800)","0","pure_quanta_power","I3";
;
CDS_LIB"pure_quanta_power"
HDL_POWER"GND";
"A"6;
%"Q_RES"
"2","(1650,5350)","0","pure_quanta","I30";
;
LOCATION"PR88"
$SEC"1"
CDS_SEC"1"
WATTAGE"1/16W"
MATERIAL"CHIP"
TOLERANCE"1%"
VALUE"2.2"
PACK_TYPE"0402LF"
CDS_LIB"pure_quanta"
PART_NUMBER"CS-2202FB01";
"A"
$PN"1"26;
"B"
$PN"2"34;
%"UNIVERSAL_GND"
"1","(2000,5100)","0","pure_quanta_power","I31";
;
CDS_LIB"pure_quanta_power"
HDL_POWER"GND";
"A"7;
%"Q_CAP"
"1","(2000,5375)","0","pure_quanta","I32";
;
LOCATION"PC112_C1P0_3"
$SEC"1"
CDS_SEC"1"
PACK_TYPE"C0402"
VOLTAGE"10V"
VALUE"2.2UF"
TOLERANCE"10%"
MATERIAL"X6S"
CDS_LIB"pure_quanta"
PART_NUMBER"CH5222KEB01";
"B"
$PN"2"7;
"A"
$PN"1"26;
%"VCC_CORE"
"1","(1650,5775)","0","pure_quanta_power","I33";
;
HDL_POWER"PVDDCR_CPU1_P0_PVCC"
CDS_LIB"pure_quanta_power";
"A"26;
%"Q_CAP"
"1","(4100,5300)","0","pure_quanta","I34";
;
LOCATION"PC116_3"
$SEC"1"
CDS_SEC"1"
VOLTAGE"25V"
VALUE"0.1UF"
TOLERANCE"10%"
MATERIAL"X7R"
PACK_TYPE"0402"
CDS_LIB"pure_quanta"
PART_NUMBER"CH4104K1B00";
"B"
$PN"2"15;
"A"
$PN"1"16;
%"UNIVERSAL_GND"
"1","(4650,600)","0","pure_quanta_power","I35";
;
CDS_LIB"pure_quanta_power"
HDL_POWER"GND";
"A"8;
%"Q_RES"
"2","(4650,825)","0","pure_quanta","I36";
;
LOCATION"PR509"
$SEC"1"
CDS_SEC"1"
PACK_TYPE"0402LF"
VALUE"1.5"
TOLERANCE"1%"
MATERIAL"EMPTY"
WATTAGE"1/8W"
CDS_LIB"pure_quanta"
PART_NUMBER"CS-1504FB00";
"A"
$PN"1"38;
"B"
$PN"2"8;
%"Q_RES"
"1","(4500,1875)","0","pure_quanta","I37";
;
LOCATION"PR89"
$SEC"1"
CDS_SEC"1"
WATTAGE"1/16W"
MATERIAL"CHIP"
PACK_TYPE"0402LF"
TOLERANCE"1%"
VALUE"5.6"
CDS_LIB"pure_quanta"
PART_NUMBER"CS-5602FB01";
"B"
$PN"2"21;
"A"
$PN"1"20;
%"Q_CAP"
"1","(4650,1350)","0","pure_quanta","I38";
;
LOCATION"PC191"
$SEC"1"
CDS_SEC"1"
PACK_TYPE"C0402"
VOLTAGE"50V"
VALUE"560PF"
TOLERANCE"10%"
MATERIAL"EMPTY"
CDS_LIB"pure_quanta"
PART_NUMBER"CH1566K1B09";
"B"
$PN"2"38;
"A"
$PN"1"33;
%"Q_RES"
"2","(1325,1025)","2","pure_quanta","I4";
;
LOCATION"PR85"
$SEC"1"
CDS_SEC"1"
WATTAGE"1/16W"
MATERIAL"EMPTY"
TOLERANCE"1%"
VALUE"8.87K"
PACK_TYPE"0402LF"
CDS_LIB"pure_quanta"
PART_NUMBER"CS28872FB01";
"A"
$PN"1"56;
"B"
$PN"2"6;
%"Q_RES"
"1","(5850,525)","0","pure_quanta","I40";
;
LOCATION"PR91"
$SEC"1"
CDS_SEC"1"
WATTAGE"1/16W"
MATERIAL"CHIP"
TOLERANCE"5%"
VALUE"0"
PACK_TYPE"0402LF"
CDS_LIB"pure_quanta"
PART_NUMBER"CS00002JB13";
"B"
$PN"2"29;
"A"
$PN"1"39;
%"Q_CAP"
"1","(5225,1750)","0","pure_quanta","I41";
;
LOCATION"PC121"
$SEC"1"
CDS_SEC"1"
VALUE"0.22UF"
VOLTAGE"16V"
TOLERANCE"10%"
PACK_TYPE"0402"
MATERIAL"X7R"
CDS_LIB"pure_quanta"
PART_NUMBER"CH4223K1B00";
"B"
$PN"2"44;
"A"
$PN"1"21;
%"Q_INDUCTOR4P_14"
"1","(6150,1400)","0","pure_quanta","I42";
;
LOCATION"PL13"
$SEC"1"
CDS_SEC"1"
VALUE"150NH"
MATERIAL"IND"
PART_TYPE"SMLF"
CDS_LIB"pure_quanta"
NEEDS_NO_SIZE"TRUE"
PART_NUMBER"CV+15^0TZ04";
"1"
$PN"1"33;
"4"
$PN"4"29;
"3"
$PN"3"27;
"2"
$PN"2"37;
%"Q_CAP"
"1","(4450,2425)","0","pure_quanta","I43";
;
LOCATION"PC117_4"
$SEC"1"
CDS_SEC"1"
TOLERANCE"10%"
VOLTAGE"25V"
VALUE"1UF"
MATERIAL"X6S"
PACK_TYPE"C0402"
CDS_LIB"pure_quanta"
PART_NUMBER"CH5104KEB02";
"B"
$PN"2"11;
"A"
$PN"1"18;
%"Q_CAP"
"1","(4850,2425)","0","pure_quanta","I44";
;
LOCATION"PC119_4"
$SEC"1"
CDS_SEC"1"
MATERIAL"X6S"
PACK_TYPE"C0805"
VALUE"22UF"
VOLTAGE"16V"
TOLERANCE"20%"
CDS_LIB"pure_quanta"
PART_NUMBER"CH6223MEA01";
"B"
$PN"2"11;
"A"
$PN"1"18;
%"UNIVERSAL_GND"
"1","(4700,3375)","0","pure_quanta_power","I45";
;
CDS_LIB"pure_quanta_power"
HDL_POWER"GND";
"A"9;
%"Q_RES"
"2","(4700,3600)","0","pure_quanta","I46";
;
LOCATION"PR510"
$SEC"1"
CDS_SEC"1"
MATERIAL"EMPTY"
WATTAGE"1/8W"
TOLERANCE"1%"
VALUE"1.5"
PACK_TYPE"0402LF"
CDS_LIB"pure_quanta"
PART_NUMBER"CS-1504FB00";
"A"
$PN"1"22;
"B"
$PN"2"9;
%"Q_CAP"
"1","(5250,2425)","0","pure_quanta","I47";
;
LOCATION"PC123_4"
$SEC"1"
CDS_SEC"1"
PACK_TYPE"C0805"
MATERIAL"X6S"
VALUE"22UF"
VOLTAGE"16V"
TOLERANCE"20%"
CDS_LIB"pure_quanta"
PART_NUMBER"CH6223MEA01";
"B"
$PN"2"11;
"A"
$PN"1"18;
%"UNIVERSAL_GND"
"1","(5625,2050)","0","pure_quanta_power","I48";
;
CDS_LIB"pure_quanta_power"
HDL_POWER"GND";
"A"11;
%"Q_CAP"
"1","(5625,2425)","0","pure_quanta","I49";
;
LOCATION"PC125_4"
$SEC"1"
CDS_SEC"1"
MATERIAL"X6S"
PACK_TYPE"C0805"
VALUE"22UF"
VOLTAGE"16V"
TOLERANCE"20%"
CDS_LIB"pure_quanta"
PART_NUMBER"CH6223MEA01";
"B"
$PN"2"11;
"A"
$PN"1"18;
%"VCC_CORE"
"1","(5625,2775)","0","pure_quanta_power","I50";
;
HDL_POWER"SW_P12V_AUX_PVDDCR_CPU1_P0_FLT"
CDS_LIB"pure_quanta_power";
"A"18;
%"Q_RES"
"1","(5850,3250)","0","pure_quanta","I51";
;
LOCATION"PR92"
$SEC"1"
CDS_SEC"1"
WATTAGE"1/16W"
MATERIAL"CHIP"
TOLERANCE"5%"
VALUE"0"
PACK_TYPE"0402LF"
CDS_LIB"pure_quanta"
PART_NUMBER"CS00002JB13";
"B"
$PN"2"31;
"A"
$PN"1"12;
%"UNIVERSAL_GND"
"1","(6975,1075)","0","pure_quanta_power","I52";
;
CDS_LIB"pure_quanta_power"
HDL_POWER"GND";
"A"27;
%"UNIVERSAL_GND"
"1","(7925,900)","0","pure_quanta_power","I53";
;
CDS_LIB"pure_quanta_power"
HDL_POWER"GND";
"A"28;
%"Q_CAP"
"1","(7500,1325)","0","pure_quanta","I54";
;
LOCATION"PC127_4"
$SEC"1"
CDS_SEC"1"
MATERIAL"X6S"
TOLERANCE"20%"
VALUE"22UF"
VOLTAGE"4V"
PACK_TYPE"C0805"
CDS_LIB"pure_quanta"
PART_NUMBER"CH622KMEA03";
"B"
$PN"2"28;
"A"
$PN"1"29;
%"Q_CAP"
"1","(7925,1325)","0","pure_quanta","I55";
;
LOCATION"PC128_4"
$SEC"1"
CDS_SEC"1"
MATERIAL"X6S"
TOLERANCE"20%"
VALUE"22UF"
VOLTAGE"4V"
PACK_TYPE"C0805"
CDS_LIB"pure_quanta"
PART_NUMBER"CH622KMEA03";
"B"
$PN"2"28;
"A"
$PN"1"29;
%"VCC_CORE"
"1","(7925,1625)","0","pure_quanta_power","I56";
;
HDL_POWER"PVDDCR_CPU1_P0"
CDS_LIB"pure_quanta_power";
"A"29;
%"Q_RES"
"1","(4525,4700)","0","pure_quanta","I57";
;
LOCATION"PR90"
$SEC"1"
CDS_SEC"1"
TOLERANCE"1%"
WATTAGE"1/16W"
PACK_TYPE"0402LF"
VALUE"5.6"
MATERIAL"CHIP"
CDS_LIB"pure_quanta"
PART_NUMBER"CS-5602FB01";
"B"
$PN"2"17;
"A"
$PN"1"19;
%"Q_CAP"
"1","(4700,4150)","0","pure_quanta","I58";
;
LOCATION"PC192"
$SEC"1"
CDS_SEC"1"
PACK_TYPE"C0402"
VOLTAGE"50V"
VALUE"560PF"
TOLERANCE"10%"
MATERIAL"EMPTY"
CDS_LIB"pure_quanta"
PART_NUMBER"CH1566K1B09";
"B"
$PN"2"22;
"A"
$PN"1"13;
%"UNIVERSAL_GND"
"1","(1475,1775)","0","pure_quanta_power","I6";
;
CDS_LIB"pure_quanta_power"
HDL_POWER"GND";
"A"10;
%"Q_CAP"
"1","(4500,5275)","0","pure_quanta","I60";
;
LOCATION"PC118_3"
$SEC"1"
CDS_SEC"1"
MATERIAL"X6S"
VALUE"1UF"
VOLTAGE"25V"
TOLERANCE"10%"
PACK_TYPE"C0402"
CDS_LIB"pure_quanta"
PART_NUMBER"CH5104KEB02";
"B"
$PN"2"15;
"A"
$PN"1"16;
%"Q_CAP"
"1","(4900,5275)","0","pure_quanta","I61";
;
LOCATION"PC120_3"
$SEC"1"
CDS_SEC"1"
MATERIAL"X6S"
PACK_TYPE"C0805"
VALUE"22UF"
VOLTAGE"16V"
TOLERANCE"20%"
CDS_LIB"pure_quanta"
PART_NUMBER"CH6223MEA01";
"B"
$PN"2"15;
"A"
$PN"1"16;
%"Q_CAP"
"1","(5250,4575)","0","pure_quanta","I62";
;
LOCATION"PC122"
$SEC"1"
CDS_SEC"1"
MATERIAL"X7R"
PACK_TYPE"0402"
VOLTAGE"16V"
TOLERANCE"10%"
VALUE"0.22UF"
CDS_LIB"pure_quanta"
PART_NUMBER"CH4223K1B00";
"B"
$PN"2"14;
"A"
$PN"1"17;
%"UNIVERSAL_GND"
"1","(5675,4925)","0","pure_quanta_power","I63";
;
CDS_LIB"pure_quanta_power"
HDL_POWER"GND";
"A"15;
%"Q_INDUCTOR4P_14"
"1","(6475,4225)","0","pure_quanta","I64";
;
LOCATION"PL14"
$SEC"1"
CDS_SEC"1"
VALUE"150NH"
MATERIAL"IND"
PART_TYPE"SMLF"
NEEDS_NO_SIZE"TRUE"
CDS_LIB"pure_quanta"
PART_NUMBER"CV+15^0TZ04";
"1"
$PN"1"13;
"4"
$PN"4"31;
"3"
$PN"3"35;
"2"
$PN"2"36;
%"Q_CAP"
"1","(5300,5275)","0","pure_quanta","I65";
;
LOCATION"PC124_3"
$SEC"1"
CDS_SEC"1"
MATERIAL"X6S"
PACK_TYPE"C0805"
VALUE"22UF"
VOLTAGE"16V"
TOLERANCE"20%"
CDS_LIB"pure_quanta"
PART_NUMBER"CH6223MEA01";
"B"
$PN"2"15;
"A"
$PN"1"16;
%"Q_CAP"
"1","(5675,5275)","0","pure_quanta","I66";
;
LOCATION"PC126_3"
$SEC"1"
CDS_SEC"1"
MATERIAL"X6S"
PACK_TYPE"C0805"
VALUE"22UF"
VOLTAGE"16V"
TOLERANCE"20%"
CDS_LIB"pure_quanta"
PART_NUMBER"CH6223MEA01";
"B"
$PN"2"15;
"A"
$PN"1"16;
%"VCC_CORE"
"1","(5675,5625)","0","pure_quanta_power","I67";
;
HDL_POWER"SW_P12V_AUX_PVDDCR_CPU1_P0_FLT"
CDS_LIB"pure_quanta_power";
"A"16;
%"Q_CAP"
"1","(7950,4150)","0","pure_quanta","I69";
;
LOCATION"PC129_3"
$SEC"1"
CDS_SEC"1"
MATERIAL"X6S"
TOLERANCE"20%"
VALUE"22UF"
VOLTAGE"4V"
PACK_TYPE"C0805"
CDS_LIB"pure_quanta"
PART_NUMBER"CH622KMEA03";
"B"
$PN"2"30;
"A"
$PN"1"31;
%"Q_CAP"
"1","(1475,1975)","0","pure_quanta","I7";
;
LOCATION"PC109"
$SEC"1"
CDS_SEC"1"
PACK_TYPE"C0402"
VOLTAGE"10V"
VALUE"2.2UF"
TOLERANCE"10%"
MATERIAL"X6S"
CDS_LIB"pure_quanta"
PART_NUMBER"CH5222KEB01";
"B"
$PN"2"10;
"A"
$PN"1"32;
%"UNIVERSAL_GND"
"1","(8375,3825)","0","pure_quanta_power","I70";
;
CDS_LIB"pure_quanta_power"
HDL_POWER"GND";
"A"30;
%"Q_CAP"
"1","(8375,4150)","0","pure_quanta","I71";
;
LOCATION"PC130_3"
$SEC"1"
CDS_SEC"1"
MATERIAL"X6S"
TOLERANCE"20%"
VALUE"22UF"
VOLTAGE"4V"
PACK_TYPE"C0805"
CDS_LIB"pure_quanta"
PART_NUMBER"CH622KMEA03";
"B"
$PN"2"30;
"A"
$PN"1"31;
%"VCC_CORE"
"1","(8375,4450)","0","pure_quanta_power","I72";
;
HDL_POWER"PVDDCR_CPU1_P0"
CDS_LIB"pure_quanta_power";
"A"31;
END.
